# S9S_MB_2U (Grand Teton) — schematic netlist excerpt (pin names and nets, part order shuffled) for the footprints in the layout excerpt that follows; sources: Cadence DE-HDL packaged netlist, KiCad conversion of 03242023_DA0F0TMBIJ0_F0T_Motherboard_J_brd_V01_OCP.brd

C402  Q_CAP  22UF 4V 20% X6S  pkg C0402  page 74 : A = PVCCFA_EHV_FIVRA_CPU0 ; B = GND
R1583  Q_RES  10K 1% CHIP  pkg 0402LF  page 183 : A = PU_PCH_PLD_3V3AUX_ALERT_N ; B = P3V3_AUX

(kicad_pcb
	(version 20260206)
	(generator "pcbnew")
	(generator_version "10.0")
	(general
		(thickness 1.6)
		(legacy_teardrops no)
	)
	(paper "A4")
	(title_block
		(title "03242023_DA0F0TMBIJ0_F0T_Motherboard_J_brd_V01_OCP.brd")
		(comment 1 "Grand Teton / footprints 302-303 of 6105")
	)
	(layers
		(0 "F.Cu" signal "TOP")
		(4 "In1.Cu" signal "GND")
		(6 "In2.Cu" signal "IN1")
		(8 "In3.Cu" signal "GND1")
		(10 "In4.Cu" signal "IN2")
		(12 "In5.Cu" signal "GND2")
		(14 "In6.Cu" signal "IN3")
		(16 "In7.Cu" signal "GND3")
		(18 "In8.Cu" signal "VCC")
		(20 "In9.Cu" signal "VCC1")
		(22 "In10.Cu" signal "GND4")
		(24 "In11.Cu" signal "IN4")
		(26 "In12.Cu" signal "GND5")
		(28 "In13.Cu" signal "IN5")
		(30 "In14.Cu" signal "GND6")
		(32 "In15.Cu" signal "IN6")
		(34 "In16.Cu" signal "GND7")
		(2 "B.Cu" signal "BOTTOM")
		(9 "F.Adhes" user "F.Adhesive")
		(11 "B.Adhes" user "B.Adhesive")
		(13 "F.Paste" user "Package Geometry/Pastemask Top")
		(15 "B.Paste" user "Package Geometry/Pastemask Bottom")
		(5 "F.SilkS" user "Ref Des/Silkscreen Top")
		(7 "B.SilkS" user "Ref Des/Silkscreen Bottom")
		(1 "F.Mask" user "Board Geometry/Soldermask Top")
		(3 "B.Mask" user "Board Geometry/Soldermask Bottom")
		(17 "Dwgs.User" user "User.Drawings")
		(19 "Cmts.User" user "User.Comments")
		(21 "Eco1.User" user "User.Eco1")
		(23 "Eco2.User" user "User.Eco2")
		(25 "Edge.Cuts" user "Board Geometry/Outline")
		(27 "Margin" user)
		(31 "F.CrtYd" user "Package Geometry/Place Bound Top")
		(29 "B.CrtYd" user "Package Geometry/Place Bound Bottom")
		(35 "F.Fab" user "Ref Des/Assembly Top")
		(33 "B.Fab" user "Ref Des/Assembly Bottom")
	)
	(footprint ""
		(layer "F.Cu")
		(at 366.48263 -260.364986 -90)
		(property "Reference" "C402"
			(at 0 0 270)
			(layer "F.SilkS")
			(hide yes)
			(effects
				(font
					(size 1.27 1.27)
				)
			)
		)
		(property "Value" ""
			(at 0 0 270)
			(layer "F.Fab")
			(effects
				(font
					(size 1.27 1.27)
				)
			)
		)
		(duplicate_pad_numbers_are_jumpers no)
		(fp_line
			(start -0.7874 0.4064)
			(end -0.7874 -0.4064)
			(stroke
				(width 0.1524)
				(type default)
			)
			(layer "F.SilkS")
		)
		(fp_line
			(start 0.7874 0.4064)
			(end -0.7874 0.4064)
			(stroke
				(width 0.1524)
				(type default)
			)
			(layer "F.SilkS")
		)
		(fp_line
			(start -0.7874 -0.4064)
			(end 0.7874 -0.4064)
			(stroke
				(width 0.1524)
				(type default)
			)
			(layer "F.SilkS")
		)
		(fp_line
			(start 0.7874 -0.4064)
			(end 0.7874 0.4064)
			(stroke
				(width 0.1524)
				(type default)
			)
			(layer "F.SilkS")
		)
		(fp_line
			(start -0.67945 0.3048)
			(end -0.67945 -0.305054)
			(stroke
				(width 0.1)
				(type default)
			)
			(layer "F.Fab")
		)
		(fp_line
			(start -0.12065 0.3048)
			(end -0.67945 0.3048)
			(stroke
				(width 0.1)
				(type default)
			)
			(layer "F.Fab")
		)
		(fp_line
			(start 0.120396 0.3048)
			(end 0.120396 0.2794)
			(stroke
				(width 0.1)
				(type default)
			)
			(layer "F.Fab")
		)
		(fp_line
			(start 0.67945 0.3048)
			(end 0.120396 0.3048)
			(stroke
				(width 0.1)
				(type default)
			)
			(layer "F.Fab")
		)
		(fp_line
			(start -0.12065 0.2794)
			(end -0.12065 0.3048)
			(stroke
				(width 0.1)
				(type default)
			)
			(layer "F.Fab")
		)
		(fp_line
			(start 0.120396 0.2794)
			(end -0.12065 0.2794)
			(stroke
				(width 0.1)
				(type default)
			)
			(layer "F.Fab")
		)
		(fp_line
			(start -0.12065 -0.2794)
			(end 0.12065 -0.2794)
			(stroke
				(width 0.1)
				(type default)
			)
			(layer "F.Fab")
		)
		(fp_line
			(start 0.12065 -0.2794)
			(end 0.12065 -0.3048)
			(stroke
				(width 0.1)
				(type default)
			)
			(layer "F.Fab")
		)
		(fp_line
			(start 0.12065 -0.3048)
			(end 0.67945 -0.3048)
			(stroke
				(width 0.1)
				(type default)
			)
			(layer "F.Fab")
		)
		(fp_line
			(start 0.67945 -0.3048)
			(end 0.67945 0.3048)
			(stroke
				(width 0.1)
				(type default)
			)
			(layer "F.Fab")
		)
		(fp_line
			(start -0.67945 -0.305054)
			(end -0.12065 -0.305054)
			(stroke
				(width 0.1)
				(type default)
			)
			(layer "F.Fab")
		)
		(fp_line
			(start -0.12065 -0.305054)
			(end -0.12065 -0.2794)
			(stroke
				(width 0.1)
				(type default)
			)
			(layer "F.Fab")
		)
		(pad "1" smd circle
			(at -0.40005 0 270)
			(size 0 0)
			(layers "F.Cu" "F.Mask" "F.Paste")
			(net "PVCCFA_EHV_FIVRA_CPU0")
		)
		(pad "2" smd circle
			(at 0.40005 0 270)
			(size 0 0)
			(layers "F.Cu" "F.Mask" "F.Paste")
			(net "GND")
		)
	)
	(footprint ""
		(layer "F.Cu")
		(at 312.443622 -39.868348 180)
		(property "Reference" "R1583"
			(at 0 0 180)
			(layer "F.SilkS")
			(hide yes)
			(effects
				(font
					(size 1.27 1.27)
				)
			)
		)
		(property "Value" ""
			(at 0 0 180)
			(layer "F.Fab")
			(effects
				(font
					(size 1.27 1.27)
				)
			)
		)
		(duplicate_pad_numbers_are_jumpers no)
		(fp_line
			(start 0.7874 0.4064)
			(end -0.7874 0.4064)
			(stroke
				(width 0.1524)
				(type default)
			)
			(layer "F.SilkS")
		)
		(fp_line
			(start 0.7874 -0.4064)
			(end 0.7874 0.4064)
			(stroke
				(width 0.1524)
				(type default)
			)
			(layer "F.SilkS")
		)
		(fp_line
			(start -0.7874 0.4064)
			(end -0.7874 -0.4064)
			(stroke
				(width 0.1524)
				(type default)
			)
			(layer "F.SilkS")
		)
		(fp_line
			(start -0.7874 -0.4064)
			(end 0.7874 -0.4064)
			(stroke
				(width 0.1524)
				(type default)
			)
			(layer "F.SilkS")
		)
		(fp_line
			(start 0.67945 0.3048)
			(end 0.120396 0.3048)
			(stroke
				(width 0.1)
				(type default)
			)
			(layer "F.Fab")
		)
		(fp_line
			(start 0.67945 -0.3048)
			(end 0.67945 0.3048)
			(stroke
				(width 0.1)
				(type default)
			)
			(layer "F.Fab")
		)
		(fp_line
			(start 0.12065 -0.2794)
			(end 0.12065 -0.3048)
			(stroke
				(width 0.1)
				(type default)
			)
			(layer "F.Fab")
		)
		(fp_line
			(start 0.12065 -0.3048)
			(end 0.67945 -0.3048)
			(stroke
				(width 0.1)
				(type default)
			)
			(layer "F.Fab")
		)
		(fp_line
			(start 0.120396 0.3048)
			(end 0.120396 0.2794)
			(stroke
				(width 0.1)
				(type default)
			)
			(layer "F.Fab")
		)
		(fp_line
			(start 0.120396 0.2794)
			(end -0.12065 0.2794)
			(stroke
				(width 0.1)
				(type default)
			)
			(layer "F.Fab")
		)
		(fp_line
			(start -0.12065 0.3048)
			(end -0.67945 0.3048)
			(stroke
				(width 0.1)
				(type default)
			)
			(layer "F.Fab")
		)
		(fp_line
			(start -0.12065 0.2794)
			(end -0.12065 0.3048)
			(stroke
				(width 0.1)
				(type default)
			)
			(layer "F.Fab")
		)
		(fp_line
			(start -0.12065 -0.2794)
			(end 0.12065 -0.2794)
			(stroke
				(width 0.1)
				(type default)
			)
			(layer "F.Fab")
		)
		(fp_line
			(start -0.12065 -0.305054)
			(end -0.12065 -0.2794)
			(stroke
				(width 0.1)
				(type default)
			)
			(layer "F.Fab")
		)
		(fp_line
			(start -0.67945 0.3048)
			(end -0.67945 -0.305054)
			(stroke
				(width 0.1)
				(type default)
			)
			(layer "F.Fab")
		)
		(fp_line
			(start -0.67945 -0.305054)
			(end -0.12065 -0.305054)
			(stroke
				(width 0.1)
				(type default)
			)
			(layer "F.Fab")
		)
		(pad "1" smd circle
			(at -0.40005 0 180)
			(size 0 0)
			(layers "F.Cu" "F.Mask" "F.Paste")
			(net "PU_PCH_PLD_3V3AUX_ALERT_N")
		)
		(pad "2" smd circle
			(at 0.40005 0 180)
			(size 0 0)
			(layers "F.Cu" "F.Mask" "F.Paste")
			(net "P3V3_AUX")
		)
	)
)
